(kicad_pcb
	(version 20260206)
	(generator "pcbnew")
	(generator_version "10.0")
	(general
		(thickness 1.6)
		(legacy_teardrops no)
	)
	(paper "A4")
	(title_block
		(title "fcb — 12433-1M.1206WZS1330.brd")
		(comment 1 "Open Vault / Knox (Wiwynn) / footprints 379-384 of 495")
	)
	(layers
		(0 "F.Cu" signal "TOP")
		(4 "In1.Cu" signal "L2GND")
		(6 "In2.Cu" signal "L3VCC")
		(2 "B.Cu" signal "BOTTOM")
		(9 "F.Adhes" user "F.Adhesive")
		(11 "B.Adhes" user "B.Adhesive")
		(13 "F.Paste" user "Package Geometry/Pastemask Top")
		(15 "B.Paste" user "Package Geometry/Pastemask Bottom")
		(5 "F.SilkS" user "Ref Des/Silkscreen Top")
		(7 "B.SilkS" user "Ref Des/Silkscreen Bottom")
		(1 "F.Mask" user "Board Geometry/Soldermask Top")
		(3 "B.Mask" user "Board Geometry/Soldermask Bottom")
		(17 "Dwgs.User" user "User.Drawings")
		(19 "Cmts.User" user "User.Comments")
		(21 "Eco1.User" user "User.Eco1")
		(23 "Eco2.User" user "User.Eco2")
		(25 "Edge.Cuts" user "Board Geometry/Outline")
		(27 "Margin" user)
		(31 "F.CrtYd" user "Package Geometry/Place Bound Top")
		(29 "B.CrtYd" user "Package Geometry/Place Bound Bottom")
		(35 "F.Fab" user "Ref Des/Assembly Top")
		(33 "B.Fab" user "Ref Des/Assembly Bottom")
	)
	(footprint ""
		(layer "F.Cu")
		(at 35.0266 -378.3076 180)
		(property "Reference" "PR51"
			(at 0 0 180)
			(layer "F.SilkS")
			(hide yes)
			(effects
				(font
					(size 1.27 1.27)
				)
			)
		)
		(property "Value" "10R2F-L-GP"
			(at 0.064008 -3.993896 180)
			(unlocked yes)
			(layer "F.Fab")
			(hide yes)
			(effects
				(font
					(size 1.016 1.016)
					(thickness 0.1524)
				)
			)
		)
		(property "Device Type" "R402H14"
			(at 0.064008 -5.517896 180)
			(unlocked yes)
			(layer "F.Fab")
			(hide yes)
			(effects
				(font
					(size 1.016 1.016)
					(thickness 0.1524)
				)
			)
		)
		(duplicate_pad_numbers_are_jumpers no)
		(fp_line
			(start 0.508 -0.9398)
			(end -0.508 -0.9398)
			(stroke
				(width 0.1524)
				(type default)
			)
			(layer "F.SilkS")
		)
		(fp_line
			(start -0.508 -0.9398)
			(end -0.508 0.9398)
			(stroke
				(width 0.1524)
				(type default)
			)
			(layer "F.SilkS")
		)
		(fp_rect
			(start -0.508 0.9398)
			(end 0.508 -0.9398)
			(stroke
				(width 0)
				(type default)
			)
			(fill no)
			(layer "F.CrtYd")
		)
		(fp_rect
			(start -0.508 0.9398)
			(end 0.508 -0.9398)
			(stroke
				(width 0)
				(type default)
			)
			(fill no)
			(layer "F.Fab")
		)
		(pad "1" smd custom
			(at 0 -0.4445 180)
			(size 0.1397 0.1397)
			(layers "F.Cu" "F.Mask" "F.Paste")
			(net "ADM1276_GATE")
			(options
				(clearance outline)
				(anchor circle)
			)
			(primitives
				(gr_poly
					(pts
						(arc
							(start -0.1778 -0.2794)
							(mid -0.249642 -0.249642)
							(end -0.2794 -0.1778)
						)
						(arc
							(start -0.2794 0.1778)
							(mid -0.249642 0.249642)
							(end -0.1778 0.2794)
						)
						(arc
							(start 0.1778 0.2794)
							(mid 0.249642 0.249642)
							(end 0.2794 0.1778)
						)
						(arc
							(start 0.2794 -0.1778)
							(mid 0.249642 -0.249642)
							(end 0.1778 -0.2794)
						)
					)
					(width 0)
					(fill yes)
				)
			)
		)
		(pad "2" smd custom
			(at 0 0.4445 180)
			(size 0.1397 0.1397)
			(layers "F.Cu" "F.Mask" "F.Paste")
			(net "ADM1276_GATE_DRV0")
			(options
				(clearance outline)
				(anchor circle)
			)
			(primitives
				(gr_poly
					(pts
						(arc
							(start -0.1778 -0.2794)
							(mid -0.249642 -0.249642)
							(end -0.2794 -0.1778)
						)
						(arc
							(start -0.2794 0.1778)
							(mid -0.249642 0.249642)
							(end -0.1778 0.2794)
						)
						(arc
							(start 0.1778 0.2794)
							(mid 0.249642 0.249642)
							(end 0.2794 0.1778)
						)
						(arc
							(start 0.2794 -0.1778)
							(mid 0.249642 -0.249642)
							(end 0.1778 -0.2794)
						)
					)
					(width 0)
					(fill yes)
				)
			)
		)
	)
	(footprint ""
		(layer "F.Cu")
		(at 41.0464 -139.5222 -90)
		(property "Reference" "PC86"
			(at 0 0 270)
			(layer "F.SilkS")
			(hide yes)
			(effects
				(font
					(size 1.27 1.27)
				)
			)
		)
		(property "Value" "SCD01U25V2KX-3GP"
			(at 1.1811 -2.7051 270)
			(unlocked yes)
			(layer "F.Fab")
			(hide yes)
			(effects
				(font
					(size 1.016 1.016)
					(thickness 0.1524)
				)
			)
		)
		(property "Device Type" "C402H22"
			(at 1.1811 -4.2291 270)
			(unlocked yes)
			(layer "F.Fab")
			(hide yes)
			(effects
				(font
					(size 1.016 1.016)
					(thickness 0.1524)
				)
			)
		)
		(duplicate_pad_numbers_are_jumpers no)
		(fp_rect
			(start -0.4318 0.9525)
			(end 0.4318 -0.9525)
			(stroke
				(width 0)
				(type default)
			)
			(fill no)
			(layer "F.CrtYd")
		)
		(fp_rect
			(start -0.4318 0.9525)
			(end 0.4318 -0.9525)
			(stroke
				(width 0)
				(type default)
			)
			(fill no)
			(layer "F.Fab")
		)
		(pad "1" smd custom
			(at 0 -0.4445 270)
			(size 0.1524 0.1524)
			(layers "F.Cu" "F.Mask" "F.Paste")
			(net "P12VL_2490_RC")
			(options
				(clearance outline)
				(anchor circle)
			)
			(primitives
				(gr_poly
					(pts
						(arc
							(start 0.3048 -0.2032)
							(mid 0.275042 -0.275042)
							(end 0.2032 -0.3048)
						)
						(arc
							(start -0.2032 -0.3048)
							(mid -0.275042 -0.275042)
							(end -0.3048 -0.2032)
						)
						(arc
							(start -0.3048 0.2032)
							(mid -0.275042 0.275042)
							(end -0.2032 0.3048)
						)
						(arc
							(start 0.2032 0.3048)
							(mid 0.275042 0.275042)
							(end 0.3048 0.2032)
						)
					)
					(width 0)
					(fill yes)
				)
			)
		)
		(pad "2" smd custom
			(at 0 0.4445 270)
			(size 0.1524 0.1524)
			(layers "F.Cu" "F.Mask" "F.Paste")
			(net "GND")
			(options
				(clearance outline)
				(anchor circle)
			)
			(primitives
				(gr_poly
					(pts
						(arc
							(start 0.3048 -0.2032)
							(mid 0.275042 -0.275042)
							(end 0.2032 -0.3048)
						)
						(arc
							(start -0.2032 -0.3048)
							(mid -0.275042 -0.275042)
							(end -0.3048 -0.2032)
						)
						(arc
							(start -0.3048 0.2032)
							(mid -0.275042 0.275042)
							(end -0.2032 0.3048)
						)
						(arc
							(start 0.2032 0.3048)
							(mid 0.275042 0.275042)
							(end 0.3048 0.2032)
						)
					)
					(width 0)
					(fill yes)
				)
			)
		)
	)
	(footprint ""
		(layer "F.Cu")
		(at 18.669 -410.591)
		(property "Reference" "PR29"
			(at 0 0 0)
			(layer "F.SilkS")
			(hide yes)
			(effects
				(font
					(size 1.27 1.27)
				)
			)
		)
		(property "Value" "D0005RL1632F-GP-U"
			(at 3.2258 1.2954 0)
			(unlocked yes)
			(layer "F.Fab")
			(hide yes)
			(effects
				(font
					(size 1.016 1.016)
					(thickness 0.1524)
				)
			)
		)
		(property "Device Type" "RL3115-4PH45"
			(at 3.2258 -0.2286 0)
			(unlocked yes)
			(layer "F.Fab")
			(hide yes)
			(effects
				(font
					(size 1.016 1.016)
					(thickness 0.1524)
				)
			)
		)
		(duplicate_pad_numbers_are_jumpers no)
		(fp_line
			(start -2.0574 -1.7653)
			(end -2.0574 -0.4064)
			(stroke
				(width 0.3302)
				(type default)
			)
			(layer "F.SilkS")
		)
		(fp_line
			(start -1.9685 -1.651)
			(end 1.9685 -1.651)
			(stroke
				(width 0.1524)
				(type default)
			)
			(layer "F.SilkS")
		)
		(fp_line
			(start -1.9685 1.651)
			(end -1.9685 -1.651)
			(stroke
				(width 0.1524)
				(type default)
			)
			(layer "F.SilkS")
		)
		(fp_line
			(start -0.5334 -1.7653)
			(end -2.0574 -1.7653)
			(stroke
				(width 0.3302)
				(type default)
			)
			(layer "F.SilkS")
		)
		(fp_line
			(start 1.9685 -1.651)
			(end 1.9685 1.651)
			(stroke
				(width 0.1524)
				(type default)
			)
			(layer "F.SilkS")
		)
		(fp_line
			(start 1.9685 1.651)
			(end -1.9685 1.651)
			(stroke
				(width 0.1524)
				(type default)
			)
			(layer "F.SilkS")
		)
		(fp_poly
			(pts
				(xy -0.561594 -1.726946) (xy -0.053594 -2.234946) (xy -1.069594 -2.234946)
			)
			(stroke
				(width 0)
				(type default)
			)
			(fill yes)
			(layer "F.SilkS")
		)
		(fp_rect
			(start -1.524 0.7493)
			(end 1.524 -0.7493)
			(stroke
				(width 0)
				(type default)
			)
			(fill no)
			(layer "F.CrtYd")
		)
		(fp_poly
			(pts
				(xy -2.2225 1.905) (xy -2.2225 -1.905) (xy 2.2225 -1.905) (xy 2.2225 -0.7493) (xy -1.524 -0.7493)
				(xy -1.524 0.7493) (xy 1.524 0.7493) (xy 1.524 -0.7366) (xy 2.2225 -0.7366) (xy 2.2225 1.905)
			)
			(stroke
				(width 0)
				(type default)
			)
			(fill no)
			(layer "F.CrtYd")
		)
		(fp_rect
			(start -2.2225 1.905)
			(end 2.2225 -1.905)
			(stroke
				(width 0)
				(type default)
			)
			(fill no)
			(layer "F.Fab")
		)
		(pad "1" smd rect
			(at -0.5715 -0.813562)
			(size 2.286 1.143)
			(layers "F.Cu" "F.Mask" "F.Paste")
			(net "P12V_AUX")
		)
		(pad "2" smd rect
			(at -0.5715 0.813562)
			(size 2.286 1.143)
			(layers "F.Cu" "F.Mask" "F.Paste")
			(net "P12V_SENSE_TRACE")
		)
		(pad "3" smd rect
			(at 1.334008 -0.813562)
			(size 0.762 1.143)
			(layers "F.Cu" "F.Mask" "F.Paste")
			(net "SENSE+_R1")
		)
		(pad "4" smd rect
			(at 1.334008 0.813562)
			(size 0.762 1.143)
			(layers "F.Cu" "F.Mask" "F.Paste")
			(net "SENSE-_R1")
		)
		(zone
			(layer "F.Cu")
			(hatch none 0.5)
			(connect_pads
				(clearance 0)
			)
			(min_thickness 0.25)
			(keepout
				(tracks not_allowed)
				(vias allowed)
				(pads allowed)
				(copperpour not_allowed)
				(footprints allowed)
			)
			(placement
				(enabled no)
				(sheetname "")
			)
			(fill
				(thermal_gap 0.5)
				(thermal_bridge_width 0.5)
				(island_removal_mode 0)
			)
			(polygon
				(pts
					(xy 19.2405 -410.833062) (xy 19.622008 -410.833062) (xy 19.622008 -411.3403) (xy 19.2405 -411.3403)
				)
			)
		)
		(zone
			(layer "F.Cu")
			(hatch none 0.5)
			(connect_pads
				(clearance 0)
			)
			(min_thickness 0.25)
			(keepout
				(tracks allowed)
				(vias not_allowed)
				(pads allowed)
				(copperpour not_allowed)
				(footprints allowed)
			)
			(placement
				(enabled no)
				(sheetname "")
			)
			(fill
				(thermal_gap 0.5)
				(thermal_bridge_width 0.5)
				(island_removal_mode 0)
			)
			(polygon
				(pts
					(xy 19.2405 -410.833062) (xy 19.622008 -410.833062) (xy 19.622008 -411.3403) (xy 19.2405 -411.3403)
				)
			)
		)
		(zone
			(layer "F.Cu")
			(hatch none 0.5)
			(connect_pads
				(clearance 0)
			)
			(min_thickness 0.25)
			(keepout
				(tracks not_allowed)
				(vias allowed)
				(pads allowed)
				(copperpour not_allowed)
				(footprints allowed)
			)
			(placement
				(enabled no)
				(sheetname "")
			)
			(fill
				(thermal_gap 0.5)
				(thermal_bridge_width 0.5)
				(island_removal_mode 0)
			)
			(polygon
				(pts
					(xy 19.2405 -409.8417) (xy 19.622008 -409.8417) (xy 19.622008 -410.348938) (xy 19.2405 -410.348938)
				)
			)
		)
		(zone
			(layer "F.Cu")
			(hatch none 0.5)
			(connect_pads
				(clearance 0)
			)
			(min_thickness 0.25)
			(keepout
				(tracks allowed)
				(vias not_allowed)
				(pads allowed)
				(copperpour not_allowed)
				(footprints allowed)
			)
			(placement
				(enabled no)
				(sheetname "")
			)
			(fill
				(thermal_gap 0.5)
				(thermal_bridge_width 0.5)
				(island_removal_mode 0)
			)
			(polygon
				(pts
					(xy 19.2405 -409.8417) (xy 19.622008 -409.8417) (xy 19.622008 -410.348938) (xy 19.2405 -410.348938)
				)
			)
		)
	)
	(footprint ""
		(layer "F.Cu")
		(at 17.0688 -179.8828 180)
		(property "Reference" "C54"
			(at 0 0 180)
			(layer "F.SilkS")
			(hide yes)
			(effects
				(font
					(size 1.27 1.27)
				)
			)
		)
		(property "Value" "SCD1U50V3KX-GP"
			(at 0 -2.8194 180)
			(unlocked yes)
			(layer "F.Fab")
			(hide yes)
			(effects
				(font
					(size 1.016 1.016)
					(thickness 0.1524)
				)
			)
		)
		(property "Device Type" "C603H36"
			(at 0 -4.3434 180)
			(unlocked yes)
			(layer "F.Fab")
			(hide yes)
			(effects
				(font
					(size 1.016 1.016)
					(thickness 0.1524)
				)
			)
		)
		(duplicate_pad_numbers_are_jumpers no)
		(fp_line
			(start 0.508 0)
			(end -0.508 0)
			(stroke
				(width 0.2032)
				(type default)
			)
			(layer "F.SilkS")
		)
		(fp_rect
			(start -0.5842 1.3335)
			(end 0.5842 -1.3335)
			(stroke
				(width 0)
				(type default)
			)
			(fill no)
			(layer "F.CrtYd")
		)
		(fp_rect
			(start -0.5842 1.3335)
			(end 0.5842 -1.3335)
			(stroke
				(width 0)
				(type default)
			)
			(fill no)
			(layer "F.Fab")
		)
		(pad "1" smd custom
			(at 0 -0.762 180)
			(size 0.2159 0.2159)
			(layers "F.Cu" "F.Mask" "F.Paste")
			(net "P3V3")
			(options
				(clearance outline)
				(anchor circle)
			)
			(primitives
				(gr_poly
					(pts
						(arc
							(start -0.3302 -0.4318)
							(mid -0.402042 -0.402042)
							(end -0.4318 -0.3302)
						)
						(arc
							(start -0.4318 0.3302)
							(mid -0.402042 0.402042)
							(end -0.3302 0.4318)
						)
						(arc
							(start 0.3302 0.4318)
							(mid 0.402042 0.402042)
							(end 0.4318 0.3302)
						)
						(arc
							(start 0.4318 -0.3302)
							(mid 0.402042 -0.402042)
							(end 0.3302 -0.4318)
						)
					)
					(width 0)
					(fill yes)
				)
			)
		)
		(pad "2" smd custom
			(at 0 0.762 180)
			(size 0.2159 0.2159)
			(layers "F.Cu" "F.Mask" "F.Paste")
			(net "GND")
			(options
				(clearance outline)
				(anchor circle)
			)
			(primitives
				(gr_poly
					(pts
						(arc
							(start -0.3302 -0.4318)
							(mid -0.402042 -0.402042)
							(end -0.4318 -0.3302)
						)
						(arc
							(start -0.4318 0.3302)
							(mid -0.402042 0.402042)
							(end -0.3302 0.4318)
						)
						(arc
							(start 0.3302 0.4318)
							(mid 0.402042 0.402042)
							(end 0.4318 0.3302)
						)
						(arc
							(start 0.4318 -0.3302)
							(mid 0.402042 -0.402042)
							(end 0.3302 -0.4318)
						)
					)
					(width 0)
					(fill yes)
				)
			)
		)
	)
	(footprint ""
		(layer "F.Cu")
		(at 43.8912 -90.6018 90)
		(property "Reference" "TC6"
			(at 0 0 90)
			(layer "F.SilkS")
			(hide yes)
			(effects
				(font
					(size 1.27 1.27)
				)
			)
		)
		(property "Value" "ST68U16VDM-1-GP"
			(at 0 -9.6012 90)
			(unlocked yes)
			(layer "F.Fab")
			(hide yes)
			(effects
				(font
					(size 1.016 1.016)
					(thickness 0.1524)
				)
			)
		)
		(property "Device Type" "CT7343H79"
			(at 0 -11.1252 90)
			(unlocked yes)
			(layer "F.Fab")
			(hide yes)
			(effects
				(font
					(size 1.016 1.016)
					(thickness 0.1524)
				)
			)
		)
		(duplicate_pad_numbers_are_jumpers no)
		(fp_line
			(start 2.286 -4.8768)
			(end -2.286 -4.8768)
			(stroke
				(width 0.1524)
				(type default)
			)
			(layer "F.SilkS")
		)
		(fp_line
			(start -2.286 -4.8768)
			(end -2.286 -2.032)
			(stroke
				(width 0.1524)
				(type default)
			)
			(layer "F.SilkS")
		)
		(fp_line
			(start 2.1082 -4.699)
			(end -2.1082 -4.699)
			(stroke
				(width 0.508)
				(type default)
			)
			(layer "F.SilkS")
		)
		(fp_line
			(start 2.286 -2.032)
			(end 2.286 -4.8768)
			(stroke
				(width 0.1524)
				(type default)
			)
			(layer "F.SilkS")
		)
		(fp_line
			(start 2.286 2.032)
			(end 2.286 4.8768)
			(stroke
				(width 0.1524)
				(type default)
			)
			(layer "F.SilkS")
		)
		(fp_line
			(start 2.286 4.8768)
			(end -2.286 4.8768)
			(stroke
				(width 0.1524)
				(type default)
			)
			(layer "F.SilkS")
		)
		(fp_line
			(start -2.286 4.8768)
			(end -2.286 2.032)
			(stroke
				(width 0.1524)
				(type default)
			)
			(layer "F.SilkS")
		)
		(fp_rect
			(start -2.1463 3.6449)
			(end 2.1463 -3.6449)
			(stroke
				(width 0)
				(type default)
			)
			(fill no)
			(layer "F.CrtYd")
		)
		(fp_poly
			(pts
				(xy -2.54 4.953) (xy -2.54 4.2926) (xy -3.81 4.2926) (xy -3.81 -4.2926) (xy -2.54 -4.2926) (xy -2.54 -4.953)
				(xy 2.54 -4.953) (xy 2.54 -4.2926) (xy 3.81 -4.2926) (xy 3.81 -1.6256) (xy 2.1463 -1.6256) (xy 2.1463 -3.6449)
				(xy -2.1463 -3.6449) (xy -2.1463 3.6449) (xy 2.1463 3.6449) (xy 2.1463 -1.6129) (xy 3.81 -1.6129)
				(xy 3.81 4.2926) (xy 2.54 4.2926) (xy 2.54 4.953)
			)
			(stroke
				(width 0)
				(type default)
			)
			(fill no)
			(layer "F.CrtYd")
		)
		(fp_rect
			(start 2.54 4.2926)
			(end 3.81 -4.2926)
			(stroke
				(width 0)
				(type default)
			)
			(fill no)
			(layer "F.Fab")
		)
		(fp_rect
			(start -3.81 4.2926)
			(end -2.54 -4.2926)
			(stroke
				(width 0)
				(type default)
			)
			(fill no)
			(layer "F.Fab")
		)
		(fp_rect
			(start -2.54 4.953)
			(end 2.54 -4.953)
			(stroke
				(width 0)
				(type default)
			)
			(fill no)
			(layer "F.Fab")
		)
		(pad "1" smd rect
			(at 0 -3.1496 90)
			(size 2.413 2.286)
			(layers "F.Cu" "F.Mask" "F.Paste")
			(net "P12VL")
		)
		(pad "2" smd rect
			(at 0 3.1496 90)
			(size 2.413 2.286)
			(layers "F.Cu" "F.Mask" "F.Paste")
			(net "GND")
		)
		(zone
			(layer "F.Cu")
			(hatch none 0.5)
			(connect_pads
				(clearance 0)
			)
			(min_thickness 0.25)
			(keepout
				(tracks allowed)
				(vias not_allowed)
				(pads allowed)
				(copperpour not_allowed)
				(footprints allowed)
			)
			(placement
				(enabled no)
				(sheetname "")
			)
			(fill
				(thermal_gap 0.5)
				(thermal_bridge_width 0.5)
				(island_removal_mode 0)
			)
			(polygon
				(pts
					(xy 42.2021 -92.1131) (xy 39.2938 -92.1131) (xy 39.2938 -89.0905) (xy 42.1894 -89.0905) (xy 42.5196 -89.0905)
					(xy 42.5196 -92.1131)
				)
			)
		)
		(zone
			(layer "F.Cu")
			(hatch none 0.5)
			(connect_pads
				(clearance 0)
			)
			(min_thickness 0.25)
			(keepout
				(tracks allowed)
				(vias not_allowed)
				(pads allowed)
				(copperpour not_allowed)
				(footprints allowed)
			)
			(placement
				(enabled no)
				(sheetname "")
			)
			(fill
				(thermal_gap 0.5)
				(thermal_bridge_width 0.5)
				(island_removal_mode 0)
			)
			(polygon
				(pts
					(xy 48.4886 -89.0905) (xy 48.4886 -92.1131) (xy 45.593 -92.1131) (xy 45.2628 -92.1131) (xy 45.2628 -89.0905)
					(xy 45.593 -89.0905)
				)
			)
		)
	)
	(footprint ""
		(layer "F.Cu")
		(at 20.9296 -174.3456 90)
		(property "Reference" "R22"
			(at 0 0 90)
			(layer "F.SilkS")
			(hide yes)
			(effects
				(font
					(size 1.27 1.27)
				)
			)
		)
		(property "Value" "4K7R2F-GP"
			(at 0.064008 -3.993896 90)
			(unlocked yes)
			(layer "F.Fab")
			(hide yes)
			(effects
				(font
					(size 1.016 1.016)
					(thickness 0.1524)
				)
			)
		)
		(property "Device Type" "R402H16"
			(at 0.064008 -5.517896 90)
			(unlocked yes)
			(layer "F.Fab")
			(hide yes)
			(effects
				(font
					(size 1.016 1.016)
					(thickness 0.1524)
				)
			)
		)
		(duplicate_pad_numbers_are_jumpers no)
		(fp_line
			(start 0.508 -0.9398)
			(end -0.508 -0.9398)
			(stroke
				(width 0.1524)
				(type default)
			)
			(layer "F.SilkS")
		)
		(fp_line
			(start -0.508 -0.9398)
			(end -0.508 0.9398)
			(stroke
				(width 0.1524)
				(type default)
			)
			(layer "F.SilkS")
		)
		(fp_rect
			(start -0.508 0.9398)
			(end 0.508 -0.9398)
			(stroke
				(width 0)
				(type default)
			)
			(fill no)
			(layer "F.CrtYd")
		)
		(fp_rect
			(start -0.508 0.9398)
			(end 0.508 -0.9398)
			(stroke
				(width 0)
				(type default)
			)
			(fill no)
			(layer "F.Fab")
		)
		(pad "1" smd custom
			(at 0 -0.4445 90)
			(size 0.1397 0.1397)
			(layers "F.Cu" "F.Mask" "F.Paste")
			(net "P3V3")
			(options
				(clearance outline)
				(anchor circle)
			)
			(primitives
				(gr_poly
					(pts
						(arc
							(start -0.1778 -0.2794)
							(mid -0.249642 -0.249642)
							(end -0.2794 -0.1778)
						)
						(arc
							(start -0.2794 0.1778)
							(mid -0.249642 0.249642)
							(end -0.1778 0.2794)
						)
						(arc
							(start 0.1778 0.2794)
							(mid 0.249642 0.249642)
							(end 0.2794 0.1778)
						)
						(arc
							(start 0.2794 -0.1778)
							(mid 0.249642 -0.249642)
							(end 0.1778 -0.2794)
						)
					)
					(width 0)
					(fill yes)
				)
			)
		)
		(pad "2" smd custom
			(at 0 0.4445 90)
			(size 0.1397 0.1397)
			(layers "F.Cu" "F.Mask" "F.Paste")
			(net "THERMHOT#")
			(options
				(clearance outline)
				(anchor circle)
			)
			(primitives
				(gr_poly
					(pts
						(arc
							(start -0.1778 -0.2794)
							(mid -0.249642 -0.249642)
							(end -0.2794 -0.1778)
						)
						(arc
							(start -0.2794 0.1778)
							(mid -0.249642 0.249642)
							(end -0.1778 0.2794)
						)
						(arc
							(start 0.1778 0.2794)
							(mid 0.249642 0.249642)
							(end 0.2794 0.1778)
						)
						(arc
							(start 0.2794 -0.1778)
							(mid 0.249642 -0.249642)
							(end 0.1778 -0.2794)
						)
					)
					(width 0)
					(fill yes)
				)
			)
		)
	)
)
